FILE_TYPE = MULTI_PHYS_TABLE;

PART 'IDTQS3VH257PAG'

{========================================================================================}
:VALUE            | MANUF_PN         | PACK_TYPE | MATERIAL | PART_NUMBER    = STANDARD         | LIFECYCLE        | ENVCOMP | PART_NUMBER   | JEDEC_TYPE | CLASS | DESCRIPTION                          | HEIGHT   | COMPONENT_TYPE | LEAD_LENGTH | LPID | DAY        ;
{========================================================================================}
 'IDTQS3VH257PAG' | 'IDTQS3VH257PAG' | 'SMLF'    | 'IC'     | 'AL000257K00'(!) = ''               | ''               | 'YES'   | 'AL000257K00' |'TSSOP16'| 'IC'  | 'IC OTHER(16P)IDTQS3VH257PAG(TSSOP)' | '.048IN' | 'SMALLSMT'     | ''          | ''   | '20100709'
 'IDTQS3VH257PAG' | 'IDTQS3VH257PAG' | 'SMLF'    | 'EMPTY'  | 'AL000257K00'(!) = ''               | ''               | 'YES'   | 'AL000257K00' |'TSSOP16'| 'IO'  | 'IC OTHER(16P)IDTQS3VH257PAG(TSSOP)' | '.048IN' | 'SMALLSMT'     | ''          | ''   | '20100709'

END_PART

END.

